(kicad_pcb
	(version 20260206)
	(generator "pcbnew")
	(generator_version "10.0")
	(general
		(thickness 1.6)
		(legacy_teardrops no)
	)
	(paper "A4")
	(title_block
		(title "01162023_DA0F0TEBIF0_F0T_Expander_BD_F_brd_V02_OCP.brd")
		(comment 1 "Grand Teton / footprint 6619 of 9728 (PEX0), pads 1998-2117 of 2397")
	)
	(layers
		(0 "F.Cu" signal "TOP")
		(4 "In1.Cu" signal "GND")
		(6 "In2.Cu" signal "VCC")
		(8 "In3.Cu" signal "VCC1")
		(10 "In4.Cu" signal "GND1")
		(12 "In5.Cu" signal "IN1")
		(14 "In6.Cu" signal "GND2")
		(16 "In7.Cu" signal "IN2")
		(18 "In8.Cu" signal "GND3")
		(20 "In9.Cu" signal "IN3")
		(22 "In10.Cu" signal "GND4")
		(24 "In11.Cu" signal "IN4")
		(26 "In12.Cu" signal "GND5")
		(28 "In13.Cu" signal "IN5")
		(30 "In14.Cu" signal "GND6")
		(32 "In15.Cu" signal "IN6")
		(34 "In16.Cu" signal "GND7")
		(2 "B.Cu" signal "BOTTOM")
		(9 "F.Adhes" user "F.Adhesive")
		(11 "B.Adhes" user "B.Adhesive")
		(13 "F.Paste" user "Package Geometry/Pastemask Top")
		(15 "B.Paste" user "Package Geometry/Pastemask Bottom")
		(5 "F.SilkS" user "Ref Des/Silkscreen Top")
		(7 "B.SilkS" user "Ref Des/Silkscreen Bottom")
		(1 "F.Mask" user "Board Geometry/Soldermask Top")
		(3 "B.Mask" user "Board Geometry/Soldermask Bottom")
		(17 "Dwgs.User" user "User.Drawings")
		(19 "Cmts.User" user "User.Comments")
		(21 "Eco1.User" user "User.Eco1")
		(23 "Eco2.User" user "User.Eco2")
		(25 "Edge.Cuts" user "Board Geometry/Outline")
		(27 "Margin" user)
		(31 "F.CrtYd" user "Package Geometry/Place Bound Top")
		(29 "B.CrtYd" user "Package Geometry/Place Bound Bottom")
		(35 "F.Fab" user "Ref Des/Assembly Top")
		(33 "B.Fab" user "Ref Des/Assembly Bottom")
	)
	(footprint ""
		(layer "F.Cu")
		(at 59.649868 -295.89984)
		(property "Reference" "PEX0"
			(at -3.360166 35.566858 0)
			(unlocked yes)
			(layer "F.SilkS")
			(effects
				(font
					(size 2.032 1.524)
					(thickness 0.1524)
				)
				(justify left)
			)
		)
		(property "Value" ""
			(at 0 0 0)
			(layer "F.Fab")
			(effects
				(font
					(size 1.27 1.27)
				)
			)
		)
		(duplicate_pad_numbers_are_jumpers no)
		(pad "M42" smd circle
			(at 16.150082 -12.349988)
			(size 0.4572 0.4572)
			(layers "F.Cu" "F.Mask" "F.Paste")
			(net "P5E_PEX0_STN4_TX_DN<68>")
		)
		(pad "M43" smd circle
			(at 17.100042 -12.349988)
			(size 0.4572 0.4572)
			(layers "F.Cu" "F.Mask" "F.Paste")
			(net "GND")
		)
		(pad "M44" smd circle
			(at 18.050002 -12.349988)
			(size 0.4572 0.4572)
			(layers "F.Cu" "F.Mask" "F.Paste")
			(net "GND")
		)
		(pad "M45" smd circle
			(at 18.999962 -12.349988)
			(size 0.4572 0.4572)
			(layers "F.Cu" "F.Mask" "F.Paste")
			(net "GND")
		)
		(pad "M46" smd circle
			(at 19.949922 -12.349988)
			(size 0.4572 0.4572)
			(layers "F.Cu" "F.Mask" "F.Paste")
			(net "GND")
		)
		(pad "M47" smd circle
			(at 20.899882 -12.349988)
			(size 0.4572 0.4572)
			(layers "F.Cu" "F.Mask" "F.Paste")
			(net "GND")
		)
		(pad "M48" smd circle
			(at 21.850096 -12.349988)
			(size 0.4572 0.4572)
			(layers "F.Cu" "F.Mask" "F.Paste")
			(net "P5E_PEX0_STN4_RX_DP<68>")
		)
		(pad "M49" smd circle
			(at 22.800056 -12.349988)
			(size 0.4572 0.4572)
			(layers "F.Cu" "F.Mask" "F.Paste")
			(net "P5E_PEX0_STN4_RX_DN<68>")
		)
		(pad "N1" smd circle
			(at -22.800056 -11.400028)
			(size 0.4572 0.4572)
			(layers "F.Cu" "F.Mask" "F.Paste")
			(net "GND")
		)
		(pad "N2" smd circle
			(at -21.850096 -11.400028)
			(size 0.4572 0.4572)
			(layers "F.Cu" "F.Mask" "F.Paste")
			(net "GND")
		)
		(pad "N3" smd circle
			(at -20.899882 -11.400028)
			(size 0.4572 0.4572)
			(layers "F.Cu" "F.Mask" "F.Paste")
			(net "P5E_PEX0_STN7_RX_DN<118>")
		)
		(pad "N4" smd circle
			(at -19.949922 -11.400028)
			(size 0.4572 0.4572)
			(layers "F.Cu" "F.Mask" "F.Paste")
			(net "P5E_PEX0_STN7_RX_DP<118>")
		)
		(pad "N5" smd circle
			(at -18.999962 -11.400028)
			(size 0.4572 0.4572)
			(layers "F.Cu" "F.Mask" "F.Paste")
			(net "GND")
		)
		(pad "N6" smd circle
			(at -18.050002 -11.400028)
			(size 0.4572 0.4572)
			(layers "F.Cu" "F.Mask" "F.Paste")
			(net "P5E_PEX0_STN7_TX_DN<118>")
		)
		(pad "N7" smd circle
			(at -17.100042 -11.400028)
			(size 0.4572 0.4572)
			(layers "F.Cu" "F.Mask" "F.Paste")
			(net "P5E_PEX0_STN7_TX_DP<118>")
		)
		(pad "N8" smd circle
			(at -16.150082 -11.400028)
			(size 0.4572 0.4572)
			(layers "F.Cu" "F.Mask" "F.Paste")
			(net "GND")
		)
		(pad "N9" smd circle
			(at -15.200122 -11.400028)
			(size 0.4572 0.4572)
			(layers "F.Cu" "F.Mask" "F.Paste")
			(net "GND")
		)
		(pad "N10" smd circle
			(at -14.249908 -11.400028)
			(size 0.4572 0.4572)
			(layers "F.Cu" "F.Mask" "F.Paste")
			(net "GND")
		)
		(pad "N11" smd circle
			(at -13.299948 -11.400028)
			(size 0.4572 0.4572)
			(layers "F.Cu" "F.Mask" "F.Paste")
			(net "GND")
		)
		(pad "N12" smd circle
			(at -12.349988 -11.400028)
			(size 0.4572 0.4572)
			(layers "F.Cu" "F.Mask" "F.Paste")
			(net "GND")
		)
		(pad "N13" smd circle
			(at -11.400028 -11.400028)
			(size 0.4572 0.4572)
			(layers "F.Cu" "F.Mask" "F.Paste")
			(net "GND")
		)
		(pad "N14" smd circle
			(at -10.450068 -11.400028)
			(size 0.4572 0.4572)
			(layers "F.Cu" "F.Mask" "F.Paste")
			(net "GND")
		)
		(pad "N15" smd circle
			(at -9.500108 -11.400028)
			(size 0.4572 0.4572)
			(layers "F.Cu" "F.Mask" "F.Paste")
			(net "GND")
		)
		(pad "N16" smd circle
			(at -8.549894 -11.400028)
			(size 0.4572 0.4572)
			(layers "F.Cu" "F.Mask" "F.Paste")
			(net "GND")
		)
		(pad "N17" smd circle
			(at -7.599934 -11.400028)
			(size 0.4572 0.4572)
			(layers "F.Cu" "F.Mask" "F.Paste")
			(net "GND")
		)
		(pad "N18" smd circle
			(at -6.649974 -11.400028)
			(size 0.4572 0.4572)
			(layers "F.Cu" "F.Mask" "F.Paste")
			(net "GND")
		)
		(pad "N19" smd circle
			(at -5.700014 -11.400028)
			(size 0.4572 0.4572)
			(layers "F.Cu" "F.Mask" "F.Paste")
			(net "GND")
		)
		(pad "N20" smd circle
			(at -4.750054 -11.400028)
			(size 0.4572 0.4572)
			(layers "F.Cu" "F.Mask" "F.Paste")
			(net "GND")
		)
		(pad "N21" smd circle
			(at -3.800094 -11.400028)
			(size 0.4572 0.4572)
			(layers "F.Cu" "F.Mask" "F.Paste")
			(net "GND")
		)
		(pad "N22" smd circle
			(at -2.84988 -11.400028)
			(size 0.4572 0.4572)
			(layers "F.Cu" "F.Mask" "F.Paste")
			(net "GND")
		)
		(pad "N23" smd circle
			(at -1.89992 -11.400028)
			(size 0.4572 0.4572)
			(layers "F.Cu" "F.Mask" "F.Paste")
			(net "GND")
		)
		(pad "N24" smd circle
			(at -0.94996 -11.400028)
			(size 0.4572 0.4572)
			(layers "F.Cu" "F.Mask" "F.Paste")
			(net "GND")
		)
		(pad "N25" smd circle
			(at 0 -11.400028)
			(size 0.4572 0.4572)
			(layers "F.Cu" "F.Mask" "F.Paste")
			(net "GND")
		)
		(pad "N26" smd circle
			(at 0.94996 -11.400028)
			(size 0.4572 0.4572)
			(layers "F.Cu" "F.Mask" "F.Paste")
			(net "GND")
		)
		(pad "N27" smd circle
			(at 1.89992 -11.400028)
			(size 0.4572 0.4572)
			(layers "F.Cu" "F.Mask" "F.Paste")
			(net "GND")
		)
		(pad "N28" smd circle
			(at 2.84988 -11.400028)
			(size 0.4572 0.4572)
			(layers "F.Cu" "F.Mask" "F.Paste")
			(net "GND")
		)
		(pad "N29" smd circle
			(at 3.800094 -11.400028)
			(size 0.4572 0.4572)
			(layers "F.Cu" "F.Mask" "F.Paste")
			(net "GND")
		)
		(pad "N30" smd circle
			(at 4.750054 -11.400028)
			(size 0.4572 0.4572)
			(layers "F.Cu" "F.Mask" "F.Paste")
			(net "GND")
		)
		(pad "N31" smd circle
			(at 5.700014 -11.400028)
			(size 0.4572 0.4572)
			(layers "F.Cu" "F.Mask" "F.Paste")
			(net "GND")
		)
		(pad "N32" smd circle
			(at 6.649974 -11.400028)
			(size 0.4572 0.4572)
			(layers "F.Cu" "F.Mask" "F.Paste")
			(net "GND")
		)
		(pad "N33" smd circle
			(at 7.599934 -11.400028)
			(size 0.4572 0.4572)
			(layers "F.Cu" "F.Mask" "F.Paste")
			(net "GND")
		)
		(pad "N34" smd circle
			(at 8.549894 -11.400028)
			(size 0.4572 0.4572)
			(layers "F.Cu" "F.Mask" "F.Paste")
			(net "GND")
		)
		(pad "N35" smd circle
			(at 9.500108 -11.400028)
			(size 0.4572 0.4572)
			(layers "F.Cu" "F.Mask" "F.Paste")
			(net "GND")
		)
		(pad "N36" smd circle
			(at 10.450068 -11.400028)
			(size 0.4572 0.4572)
			(layers "F.Cu" "F.Mask" "F.Paste")
			(net "GND")
		)
		(pad "N37" smd circle
			(at 11.400028 -11.400028)
			(size 0.4572 0.4572)
			(layers "F.Cu" "F.Mask" "F.Paste")
			(net "GND")
		)
		(pad "N38" smd circle
			(at 12.349988 -11.400028)
			(size 0.4572 0.4572)
			(layers "F.Cu" "F.Mask" "F.Paste")
			(net "SMB_PEX0_SLAVE_SCL")
		)
		(pad "N39" smd circle
			(at 13.299948 -11.400028)
			(size 0.4572 0.4572)
			(layers "F.Cu" "F.Mask" "F.Paste")
			(net "Net_2888")
		)
		(pad "N40" smd circle
			(at 14.249908 -11.400028)
			(size 0.4572 0.4572)
			(layers "F.Cu" "F.Mask" "F.Paste")
			(net "GND")
		)
		(pad "N41" smd circle
			(at 15.200122 -11.400028)
			(size 0.4572 0.4572)
			(layers "F.Cu" "F.Mask" "F.Paste")
			(net "GND")
		)
		(pad "N42" smd circle
			(at 16.150082 -11.400028)
			(size 0.4572 0.4572)
			(layers "F.Cu" "F.Mask" "F.Paste")
			(net "GND")
		)
		(pad "N43" smd circle
			(at 17.100042 -11.400028)
			(size 0.4572 0.4572)
			(layers "F.Cu" "F.Mask" "F.Paste")
			(net "P5E_PEX0_STN4_TX_DP<67>")
		)
		(pad "N44" smd circle
			(at 18.050002 -11.400028)
			(size 0.4572 0.4572)
			(layers "F.Cu" "F.Mask" "F.Paste")
			(net "P5E_PEX0_STN4_TX_DN<67>")
		)
		(pad "N45" smd circle
			(at 18.999962 -11.400028)
			(size 0.4572 0.4572)
			(layers "F.Cu" "F.Mask" "F.Paste")
			(net "GND")
		)
		(pad "N46" smd circle
			(at 19.949922 -11.400028)
			(size 0.4572 0.4572)
			(layers "F.Cu" "F.Mask" "F.Paste")
			(net "P5E_PEX0_STN4_RX_DP<67>")
		)
		(pad "N47" smd circle
			(at 20.899882 -11.400028)
			(size 0.4572 0.4572)
			(layers "F.Cu" "F.Mask" "F.Paste")
			(net "P5E_PEX0_STN4_RX_DN<67>")
		)
		(pad "N48" smd circle
			(at 21.850096 -11.400028)
			(size 0.4572 0.4572)
			(layers "F.Cu" "F.Mask" "F.Paste")
			(net "GND")
		)
		(pad "N49" smd circle
			(at 22.800056 -11.400028)
			(size 0.4572 0.4572)
			(layers "F.Cu" "F.Mask" "F.Paste")
			(net "GND")
		)
		(pad "P1" smd circle
			(at -22.800056 -10.450068)
			(size 0.4572 0.4572)
			(layers "F.Cu" "F.Mask" "F.Paste")
			(net "P5E_PEX0_STN7_RX_DN<117>")
		)
		(pad "P2" smd circle
			(at -21.850096 -10.450068)
			(size 0.4572 0.4572)
			(layers "F.Cu" "F.Mask" "F.Paste")
			(net "P5E_PEX0_STN7_RX_DP<117>")
		)
		(pad "P3" smd circle
			(at -20.899882 -10.450068)
			(size 0.4572 0.4572)
			(layers "F.Cu" "F.Mask" "F.Paste")
			(net "GND")
		)
		(pad "P4" smd circle
			(at -19.949922 -10.450068)
			(size 0.4572 0.4572)
			(layers "F.Cu" "F.Mask" "F.Paste")
			(net "GND")
		)
		(pad "P5" smd circle
			(at -18.999962 -10.450068)
			(size 0.4572 0.4572)
			(layers "F.Cu" "F.Mask" "F.Paste")
			(net "GND")
		)
		(pad "P6" smd circle
			(at -18.050002 -10.450068)
			(size 0.4572 0.4572)
			(layers "F.Cu" "F.Mask" "F.Paste")
			(net "GND")
		)
		(pad "P7" smd circle
			(at -17.100042 -10.450068)
			(size 0.4572 0.4572)
			(layers "F.Cu" "F.Mask" "F.Paste")
			(net "GND")
		)
		(pad "P8" smd circle
			(at -16.150082 -10.450068)
			(size 0.4572 0.4572)
			(layers "F.Cu" "F.Mask" "F.Paste")
			(net "P5E_PEX0_STN7_TX_DN<117>")
		)
		(pad "P9" smd circle
			(at -15.200122 -10.450068)
			(size 0.4572 0.4572)
			(layers "F.Cu" "F.Mask" "F.Paste")
			(net "P5E_PEX0_STN7_TX_DP<117>")
		)
		(pad "P10" smd circle
			(at -14.249908 -10.450068)
			(size 0.4572 0.4572)
			(layers "F.Cu" "F.Mask" "F.Paste")
			(net "GND")
		)
		(pad "P11" smd circle
			(at -13.299948 -10.450068)
			(size 0.4572 0.4572)
			(layers "F.Cu" "F.Mask" "F.Paste")
			(net "GND")
		)
		(pad "P12" smd circle
			(at -12.349988 -10.450068)
			(size 0.4572 0.4572)
			(layers "F.Cu" "F.Mask" "F.Paste")
			(net "GND")
		)
		(pad "P13" smd circle
			(at -11.400028 -10.450068)
			(size 0.4572 0.4572)
			(layers "F.Cu" "F.Mask" "F.Paste")
			(net "GND")
		)
		(pad "P14" smd circle
			(at -10.450068 -10.450068)
			(size 0.4572 0.4572)
			(layers "F.Cu" "F.Mask" "F.Paste")
			(net "GND")
		)
		(pad "P15" smd circle
			(at -9.500108 -10.450068)
			(size 0.4572 0.4572)
			(layers "F.Cu" "F.Mask" "F.Paste")
			(net "GND")
		)
		(pad "P16" smd circle
			(at -8.549894 -10.450068)
			(size 0.4572 0.4572)
			(layers "F.Cu" "F.Mask" "F.Paste")
			(net "GND")
		)
		(pad "P17" smd circle
			(at -7.599934 -10.450068)
			(size 0.4572 0.4572)
			(layers "F.Cu" "F.Mask" "F.Paste")
			(net "GND")
		)
		(pad "P18" smd circle
			(at -6.649974 -10.450068)
			(size 0.4572 0.4572)
			(layers "F.Cu" "F.Mask" "F.Paste")
			(net "GND")
		)
		(pad "P19" smd circle
			(at -5.700014 -10.450068)
			(size 0.4572 0.4572)
			(layers "F.Cu" "F.Mask" "F.Paste")
			(net "GND")
		)
		(pad "P20" smd circle
			(at -4.750054 -10.450068)
			(size 0.4572 0.4572)
			(layers "F.Cu" "F.Mask" "F.Paste")
			(net "GND")
		)
		(pad "P21" smd circle
			(at -3.800094 -10.450068)
			(size 0.4572 0.4572)
			(layers "F.Cu" "F.Mask" "F.Paste")
			(net "GND")
		)
		(pad "P22" smd circle
			(at -2.84988 -10.450068)
			(size 0.4572 0.4572)
			(layers "F.Cu" "F.Mask" "F.Paste")
			(net "GND")
		)
		(pad "P23" smd circle
			(at -1.89992 -10.450068)
			(size 0.4572 0.4572)
			(layers "F.Cu" "F.Mask" "F.Paste")
			(net "GND")
		)
		(pad "P24" smd circle
			(at -0.94996 -10.450068)
			(size 0.4572 0.4572)
			(layers "F.Cu" "F.Mask" "F.Paste")
			(net "GND")
		)
		(pad "P25" smd circle
			(at 0 -10.450068)
			(size 0.4572 0.4572)
			(layers "F.Cu" "F.Mask" "F.Paste")
			(net "GND")
		)
		(pad "P26" smd circle
			(at 0.94996 -10.450068)
			(size 0.4572 0.4572)
			(layers "F.Cu" "F.Mask" "F.Paste")
			(net "GND")
		)
		(pad "P27" smd circle
			(at 1.89992 -10.450068)
			(size 0.4572 0.4572)
			(layers "F.Cu" "F.Mask" "F.Paste")
			(net "GND")
		)
		(pad "P28" smd circle
			(at 2.84988 -10.450068)
			(size 0.4572 0.4572)
			(layers "F.Cu" "F.Mask" "F.Paste")
			(net "GND")
		)
		(pad "P29" smd circle
			(at 3.800094 -10.450068)
			(size 0.4572 0.4572)
			(layers "F.Cu" "F.Mask" "F.Paste")
			(net "GND")
		)
		(pad "P30" smd circle
			(at 4.750054 -10.450068)
			(size 0.4572 0.4572)
			(layers "F.Cu" "F.Mask" "F.Paste")
			(net "GND")
		)
		(pad "P31" smd circle
			(at 5.700014 -10.450068)
			(size 0.4572 0.4572)
			(layers "F.Cu" "F.Mask" "F.Paste")
			(net "GND")
		)
		(pad "P32" smd circle
			(at 6.649974 -10.450068)
			(size 0.4572 0.4572)
			(layers "F.Cu" "F.Mask" "F.Paste")
			(net "GND")
		)
		(pad "P33" smd circle
			(at 7.599934 -10.450068)
			(size 0.4572 0.4572)
			(layers "F.Cu" "F.Mask" "F.Paste")
			(net "GND")
		)
		(pad "P34" smd circle
			(at 8.549894 -10.450068)
			(size 0.4572 0.4572)
			(layers "F.Cu" "F.Mask" "F.Paste")
			(net "GND")
		)
		(pad "P35" smd circle
			(at 9.500108 -10.450068)
			(size 0.4572 0.4572)
			(layers "F.Cu" "F.Mask" "F.Paste")
			(net "GND")
		)
		(pad "P36" smd circle
			(at 10.450068 -10.450068)
			(size 0.4572 0.4572)
			(layers "F.Cu" "F.Mask" "F.Paste")
			(net "Net_484")
		)
		(pad "P37" smd circle
			(at 11.400028 -10.450068)
			(size 0.4572 0.4572)
			(layers "F.Cu" "F.Mask" "F.Paste")
			(net "GND")
		)
		(pad "P38" smd circle
			(at 12.349988 -10.450068)
			(size 0.4572 0.4572)
			(layers "F.Cu" "F.Mask" "F.Paste")
			(net "RST_PEX0_S3_PERST_R_N")
		)
		(pad "P39" smd circle
			(at 13.299948 -10.450068)
			(size 0.4572 0.4572)
			(layers "F.Cu" "F.Mask" "F.Paste")
			(net "RST_PEX0_S1_PERST_R_N")
		)
		(pad "P40" smd circle
			(at 14.249908 -10.450068)
			(size 0.4572 0.4572)
			(layers "F.Cu" "F.Mask" "F.Paste")
			(net "GND")
		)
		(pad "P41" smd circle
			(at 15.200122 -10.450068)
			(size 0.4572 0.4572)
			(layers "F.Cu" "F.Mask" "F.Paste")
			(net "P5E_PEX0_STN4_TX_DP<66>")
		)
		(pad "P42" smd circle
			(at 16.150082 -10.450068)
			(size 0.4572 0.4572)
			(layers "F.Cu" "F.Mask" "F.Paste")
			(net "P5E_PEX0_STN4_TX_DN<66>")
		)
		(pad "P43" smd circle
			(at 17.100042 -10.450068)
			(size 0.4572 0.4572)
			(layers "F.Cu" "F.Mask" "F.Paste")
			(net "GND")
		)
		(pad "P44" smd circle
			(at 18.050002 -10.450068)
			(size 0.4572 0.4572)
			(layers "F.Cu" "F.Mask" "F.Paste")
			(net "GND")
		)
		(pad "P45" smd circle
			(at 18.999962 -10.450068)
			(size 0.4572 0.4572)
			(layers "F.Cu" "F.Mask" "F.Paste")
			(net "GND")
		)
		(pad "P46" smd circle
			(at 19.949922 -10.450068)
			(size 0.4572 0.4572)
			(layers "F.Cu" "F.Mask" "F.Paste")
			(net "GND")
		)
		(pad "P47" smd circle
			(at 20.899882 -10.450068)
			(size 0.4572 0.4572)
			(layers "F.Cu" "F.Mask" "F.Paste")
			(net "GND")
		)
		(pad "P48" smd circle
			(at 21.850096 -10.450068)
			(size 0.4572 0.4572)
			(layers "F.Cu" "F.Mask" "F.Paste")
			(net "P5E_PEX0_STN4_RX_DP<66>")
		)
		(pad "P49" smd circle
			(at 22.800056 -10.450068)
			(size 0.4572 0.4572)
			(layers "F.Cu" "F.Mask" "F.Paste")
			(net "P5E_PEX0_STN4_RX_DN<66>")
		)
		(pad "R1" smd circle
			(at -22.800056 -9.500108)
			(size 0.4572 0.4572)
			(layers "F.Cu" "F.Mask" "F.Paste")
			(net "GND")
		)
		(pad "R2" smd circle
			(at -21.850096 -9.500108)
			(size 0.4572 0.4572)
			(layers "F.Cu" "F.Mask" "F.Paste")
			(net "GND")
		)
		(pad "R3" smd circle
			(at -20.899882 -9.500108)
			(size 0.4572 0.4572)
			(layers "F.Cu" "F.Mask" "F.Paste")
			(net "P5E_PEX0_STN7_RX_DN<116>")
		)
		(pad "R4" smd circle
			(at -19.949922 -9.500108)
			(size 0.4572 0.4572)
			(layers "F.Cu" "F.Mask" "F.Paste")
			(net "P5E_PEX0_STN7_RX_DP<116>")
		)
		(pad "R5" smd circle
			(at -18.999962 -9.500108)
			(size 0.4572 0.4572)
			(layers "F.Cu" "F.Mask" "F.Paste")
			(net "GND")
		)
		(pad "R6" smd circle
			(at -18.050002 -9.500108)
			(size 0.4572 0.4572)
			(layers "F.Cu" "F.Mask" "F.Paste")
			(net "P5E_PEX0_STN7_TX_DN<116>")
		)
		(pad "R7" smd circle
			(at -17.100042 -9.500108)
			(size 0.4572 0.4572)
			(layers "F.Cu" "F.Mask" "F.Paste")
			(net "P5E_PEX0_STN7_TX_DP<116>")
		)
		(pad "R8" smd circle
			(at -16.150082 -9.500108)
			(size 0.4572 0.4572)
			(layers "F.Cu" "F.Mask" "F.Paste")
			(net "GND")
		)
		(pad "R9" smd circle
			(at -15.200122 -9.500108)
			(size 0.4572 0.4572)
			(layers "F.Cu" "F.Mask" "F.Paste")
			(net "GND")
		)
		(pad "R10" smd circle
			(at -14.249908 -9.500108)
			(size 0.4572 0.4572)
			(layers "F.Cu" "F.Mask" "F.Paste")
			(net "GND")
		)
		(pad "R11" smd circle
			(at -13.299948 -9.500108)
			(size 0.4572 0.4572)
			(layers "F.Cu" "F.Mask" "F.Paste")
			(net "GND")
		)
		(pad "R12" smd circle
			(at -12.349988 -9.500108)
			(size 0.4572 0.4572)
			(layers "F.Cu" "F.Mask" "F.Paste")
			(net "GND")
		)
		(pad "R13" smd circle
			(at -11.400028 -9.500108)
			(size 0.4572 0.4572)
			(layers "F.Cu" "F.Mask" "F.Paste")
			(net "GND")
		)
		(pad "R14" smd circle
			(at -10.450068 -9.500108)
			(size 0.4572 0.4572)
			(layers "F.Cu" "F.Mask" "F.Paste")
			(net "GND")
		)
	)
)
